# TIMECARD (Time Appliance Project (Time Card)) — schematic netlist excerpt (pin names and nets, part order shuffled) for the footprints in the layout excerpt that follows; sources: Cadence DE-HDL packaged netlist, KiCad conversion of R4006-B0001-02_R01.brd

CR12  DIODE_3F  pkg DPAK_3_V3  page 27
  A_1  = XP12R0V_PCIE
  A_2  = XP12R0V_EXT
  C  = XP12R0V_IN

(kicad_pcb
	(version 20260206)
	(generator "pcbnew")
	(generator_version "10.0")
	(general
		(thickness 1.6)
		(legacy_teardrops no)
	)
	(paper "A4")
	(title_block
		(title "timecard-production-celestica-r4006 — R4006-B0001-02_R01.brd")
		(comment 1 "Time Appliance Project (Time Card) / footprint 199 of 1113 (CR12), pads 1-3 of 3")
	)
	(layers
		(0 "F.Cu" signal "TOP")
		(4 "In1.Cu" signal "L02_GND1")
		(6 "In2.Cu" signal "L03_SIG1")
		(8 "In3.Cu" signal "L04_GND2")
		(10 "In4.Cu" signal "L05_VCC1")
		(12 "In5.Cu" signal "L06_VCC2")
		(14 "In6.Cu" signal "L07_GND3")
		(16 "In7.Cu" signal "L08_SIG2")
		(18 "In8.Cu" signal "L09_GND4")
		(2 "B.Cu" signal "BOTTOM")
		(9 "F.Adhes" user "F.Adhesive")
		(11 "B.Adhes" user "B.Adhesive")
		(13 "F.Paste" user "Package Geometry/Pastemask Top")
		(15 "B.Paste" user "Package Geometry/Pastemask Bottom")
		(5 "F.SilkS" user "Ref Des/Silkscreen Top")
		(7 "B.SilkS" user "Ref Des/Silkscreen Bottom")
		(1 "F.Mask" user "Board Geometry/Soldermask Top")
		(3 "B.Mask" user "Board Geometry/Soldermask Bottom")
		(17 "Dwgs.User" user "User.Drawings")
		(19 "Cmts.User" user "User.Comments")
		(21 "Eco1.User" user "User.Eco1")
		(23 "Eco2.User" user "User.Eco2")
		(25 "Edge.Cuts" user "Board Geometry/Outline")
		(27 "Margin" user)
		(31 "F.CrtYd" user "Package Geometry/Place Bound Top")
		(29 "B.CrtYd" user "Package Geometry/Place Bound Bottom")
		(35 "F.Fab" user "Ref Des/Assembly Top")
		(33 "B.Fab" user "Ref Des/Assembly Bottom")
	)
	(footprint ""
		(layer "F.Cu")
		(at 19.8882 -100.1014)
		(property "Reference" "CR12"
			(at -0.4572 8.19277 0)
			(unlocked yes)
			(layer "F.SilkS")
			(effects
				(font
					(size 0.7874 0.5842)
					(thickness 0.1524)
				)
			)
		)
		(property "Value" ""
			(at 0 0 0)
			(layer "F.Fab")
			(effects
				(font
					(size 1.27 1.27)
				)
			)
		)
		(property "Device Type" "DIODE_3F-G122-10080-01"
			(at -0.1524 8.061706 0)
			(unlocked yes)
			(layer "F.Fab")
			(hide yes)
			(effects
				(font
					(size 0.7874 0.5842)
					(thickness 0.1524)
				)
			)
		)
		(property "User Part Number" "PARTNUM*"
			(at -0.1524 9.052306 0)
			(unlocked yes)
			(layer "Cmts.User")
			(hide yes)
			(effects
				(font
					(size 0.7874 0.5842)
					(thickness 0.1524)
				)
			)
		)
		(duplicate_pad_numbers_are_jumpers no)
		(pad "1" smd rect
			(at -2.286 5.207)
			(size 1.6002 2.9972)
			(layers "F.Cu" "F.Mask" "F.Paste")
			(net "XP12R0V_PCIE")
		)
		(pad "2" smd rect
			(at 2.286 5.207)
			(size 1.6002 2.9972)
			(layers "F.Cu" "F.Mask" "F.Paste")
			(net "XP12R0V_EXT")
		)
		(pad "3" smd rect
			(at 0 -1.9558)
			(size 5.7912 6.1976)
			(layers "F.Cu" "F.Mask" "F.Paste")
			(net "XP12R0V_IN")
		)
	)
)
